(kicad_pcb
	(version 20260206)
	(generator "pcbnew")
	(generator_version "10.0")
	(general
		(thickness 1.6)
		(legacy_teardrops no)
	)
	(paper "A4")
	(title_block
		(title "01162023_DA0F0TEBIF0_F0T_Expander_BD_F_brd_V02_OCP.brd")
		(comment 1 "Grand Teton / footprints 7056-7058 of 9728")
	)
	(layers
		(0 "F.Cu" signal "TOP")
		(4 "In1.Cu" signal "GND")
		(6 "In2.Cu" signal "VCC")
		(8 "In3.Cu" signal "VCC1")
		(10 "In4.Cu" signal "GND1")
		(12 "In5.Cu" signal "IN1")
		(14 "In6.Cu" signal "GND2")
		(16 "In7.Cu" signal "IN2")
		(18 "In8.Cu" signal "GND3")
		(20 "In9.Cu" signal "IN3")
		(22 "In10.Cu" signal "GND4")
		(24 "In11.Cu" signal "IN4")
		(26 "In12.Cu" signal "GND5")
		(28 "In13.Cu" signal "IN5")
		(30 "In14.Cu" signal "GND6")
		(32 "In15.Cu" signal "IN6")
		(34 "In16.Cu" signal "GND7")
		(2 "B.Cu" signal "BOTTOM")
		(9 "F.Adhes" user "F.Adhesive")
		(11 "B.Adhes" user "B.Adhesive")
		(13 "F.Paste" user "Package Geometry/Pastemask Top")
		(15 "B.Paste" user "Package Geometry/Pastemask Bottom")
		(5 "F.SilkS" user "Ref Des/Silkscreen Top")
		(7 "B.SilkS" user "Ref Des/Silkscreen Bottom")
		(1 "F.Mask" user "Board Geometry/Soldermask Top")
		(3 "B.Mask" user "Board Geometry/Soldermask Bottom")
		(17 "Dwgs.User" user "User.Drawings")
		(19 "Cmts.User" user "User.Comments")
		(21 "Eco1.User" user "User.Eco1")
		(23 "Eco2.User" user "User.Eco2")
		(25 "Edge.Cuts" user "Board Geometry/Outline")
		(27 "Margin" user)
		(31 "F.CrtYd" user "Package Geometry/Place Bound Top")
		(29 "B.CrtYd" user "Package Geometry/Place Bound Bottom")
		(35 "F.Fab" user "Ref Des/Assembly Top")
		(33 "B.Fab" user "Ref Des/Assembly Bottom")
	)
	(footprint ""
		(layer "F.Cu")
		(at 331.147166 -21.37156)
		(property "Reference" "C3950"
			(at 0 0 0)
			(layer "F.SilkS")
			(hide yes)
			(effects
				(font
					(size 1.27 1.27)
				)
			)
		)
		(property "Value" ""
			(at 0 0 0)
			(layer "F.Fab")
			(effects
				(font
					(size 1.27 1.27)
				)
			)
		)
		(duplicate_pad_numbers_are_jumpers no)
		(fp_line
			(start -0.7874 -0.4064)
			(end 0.7874 -0.4064)
			(stroke
				(width 0.1524)
				(type default)
			)
			(layer "F.SilkS")
		)
		(fp_line
			(start -0.7874 0.4064)
			(end -0.7874 -0.4064)
			(stroke
				(width 0.1524)
				(type default)
			)
			(layer "F.SilkS")
		)
		(fp_line
			(start 0.7874 -0.4064)
			(end 0.7874 0.4064)
			(stroke
				(width 0.1524)
				(type default)
			)
			(layer "F.SilkS")
		)
		(fp_line
			(start 0.7874 0.4064)
			(end -0.7874 0.4064)
			(stroke
				(width 0.1524)
				(type default)
			)
			(layer "F.SilkS")
		)
		(fp_line
			(start -0.67945 -0.305054)
			(end -0.12065 -0.305054)
			(stroke
				(width 0.1)
				(type default)
			)
			(layer "F.Fab")
		)
		(fp_line
			(start -0.67945 0.3048)
			(end -0.67945 -0.305054)
			(stroke
				(width 0.1)
				(type default)
			)
			(layer "F.Fab")
		)
		(fp_line
			(start -0.12065 -0.305054)
			(end -0.12065 -0.2794)
			(stroke
				(width 0.1)
				(type default)
			)
			(layer "F.Fab")
		)
		(fp_line
			(start -0.12065 -0.2794)
			(end 0.12065 -0.2794)
			(stroke
				(width 0.1)
				(type default)
			)
			(layer "F.Fab")
		)
		(fp_line
			(start -0.12065 0.2794)
			(end -0.12065 0.3048)
			(stroke
				(width 0.1)
				(type default)
			)
			(layer "F.Fab")
		)
		(fp_line
			(start -0.12065 0.3048)
			(end -0.67945 0.3048)
			(stroke
				(width 0.1)
				(type default)
			)
			(layer "F.Fab")
		)
		(fp_line
			(start 0.120396 0.2794)
			(end -0.12065 0.2794)
			(stroke
				(width 0.1)
				(type default)
			)
			(layer "F.Fab")
		)
		(fp_line
			(start 0.120396 0.3048)
			(end 0.120396 0.2794)
			(stroke
				(width 0.1)
				(type default)
			)
			(layer "F.Fab")
		)
		(fp_line
			(start 0.12065 -0.3048)
			(end 0.67945 -0.3048)
			(stroke
				(width 0.1)
				(type default)
			)
			(layer "F.Fab")
		)
		(fp_line
			(start 0.12065 -0.2794)
			(end 0.12065 -0.3048)
			(stroke
				(width 0.1)
				(type default)
			)
			(layer "F.Fab")
		)
		(fp_line
			(start 0.67945 -0.3048)
			(end 0.67945 0.3048)
			(stroke
				(width 0.1)
				(type default)
			)
			(layer "F.Fab")
		)
		(fp_line
			(start 0.67945 0.3048)
			(end 0.120396 0.3048)
			(stroke
				(width 0.1)
				(type default)
			)
			(layer "F.Fab")
		)
		(pad "1" smd circle
			(at -0.40005 0)
			(size 0 0)
			(layers "F.Cu" "F.Mask" "F.Paste")
			(net "P12V_SSD11")
		)
		(pad "2" smd circle
			(at 0.40005 0)
			(size 0 0)
			(layers "F.Cu" "F.Mask" "F.Paste")
			(net "GND")
		)
	)
	(footprint ""
		(layer "F.Cu")
		(at 82.661506 -120.476772 180)
		(property "Reference" "C30"
			(at 0 0 180)
			(layer "F.SilkS")
			(hide yes)
			(effects
				(font
					(size 1.27 1.27)
				)
			)
		)
		(property "Value" ""
			(at 0 0 180)
			(layer "F.Fab")
			(effects
				(font
					(size 1.27 1.27)
				)
			)
		)
		(duplicate_pad_numbers_are_jumpers no)
		(fp_line
			(start 0.299974 0.150114)
			(end -0.299974 0.150114)
			(stroke
				(width 0.1)
				(type default)
			)
			(layer "F.Fab")
		)
		(fp_line
			(start 0.299974 -0.150114)
			(end 0.299974 0.150114)
			(stroke
				(width 0.1)
				(type default)
			)
			(layer "F.Fab")
		)
		(fp_line
			(start -0.299974 0.150114)
			(end -0.299974 -0.150114)
			(stroke
				(width 0.1)
				(type default)
			)
			(layer "F.Fab")
		)
		(fp_line
			(start -0.299974 -0.150114)
			(end 0.299974 -0.150114)
			(stroke
				(width 0.1)
				(type default)
			)
			(layer "F.Fab")
		)
		(pad "1" smd rect
			(at -0.2667 0 180)
			(size 0.3048 0.381)
			(layers "F.Cu" "F.Mask" "F.Paste")
			(net "P5E_PEX0_STN0_TX_DN<1>")
		)
		(pad "2" smd rect
			(at 0.2667 0 180)
			(size 0.3048 0.381)
			(layers "F.Cu" "F.Mask" "F.Paste")
			(net "P5E_PEX0_STN0_TX_C_DN<1>")
		)
	)
	(footprint ""
		(layer "F.Cu")
		(at 139.556744 -206.213964 90)
		(property "Reference" "U98"
			(at -5.860034 -6.613144 0)
			(unlocked yes)
			(layer "F.SilkS")
			(effects
				(font
					(size 0.7874 0.5842)
					(thickness 0.1524)
				)
				(justify left)
			)
		)
		(property "Value" ""
			(at 0 0 90)
			(layer "F.Fab")
			(effects
				(font
					(size 1.27 1.27)
				)
			)
		)
		(duplicate_pad_numbers_are_jumpers no)
		(fp_line
			(start 5.050028 -5.050028)
			(end 4.0386 -5.050028)
			(stroke
				(width 0.1524)
				(type default)
			)
			(layer "F.SilkS")
		)
		(fp_line
			(start -4.0386 -5.050028)
			(end -5.050028 -5.050028)
			(stroke
				(width 0.1524)
				(type default)
			)
			(layer "F.SilkS")
		)
		(fp_line
			(start -5.050028 -5.050028)
			(end -5.050028 -4.0386)
			(stroke
				(width 0.1524)
				(type default)
			)
			(layer "F.SilkS")
		)
		(fp_line
			(start 5.050028 -4.0386)
			(end 5.050028 -5.050028)
			(stroke
				(width 0.1524)
				(type default)
			)
			(layer "F.SilkS")
		)
		(fp_line
			(start -5.050028 4.0386)
			(end -5.050028 5.050028)
			(stroke
				(width 0.1524)
				(type default)
			)
			(layer "F.SilkS")
		)
		(fp_line
			(start 5.050028 5.050028)
			(end 5.050028 4.0386)
			(stroke
				(width 0.1524)
				(type default)
			)
			(layer "F.SilkS")
		)
		(fp_line
			(start 4.0386 5.050028)
			(end 5.050028 5.050028)
			(stroke
				(width 0.1524)
				(type default)
			)
			(layer "F.SilkS")
		)
		(fp_line
			(start -5.050028 5.050028)
			(end -4.0386 5.050028)
			(stroke
				(width 0.1524)
				(type default)
			)
			(layer "F.SilkS")
		)
		(fp_poly
			(pts
				(xy -6.706362 -5.238242) (xy -7.424928 -4.519676) (xy -6.347206 -4.16052)
			)
			(stroke
				(width 0)
				(type default)
			)
			(fill yes)
			(layer "F.SilkS")
		)
		(fp_line
			(start 5.050028 -5.050028)
			(end -5.050028 -5.050028)
			(stroke
				(width 0.1)
				(type default)
			)
			(layer "F.Fab")
		)
		(fp_line
			(start -5.050028 -5.050028)
			(end -5.050028 5.050028)
			(stroke
				(width 0.1)
				(type default)
			)
			(layer "F.Fab")
		)
		(fp_line
			(start 5.050028 5.050028)
			(end 5.050028 -5.050028)
			(stroke
				(width 0.1)
				(type default)
			)
			(layer "F.Fab")
		)
		(fp_line
			(start -5.050028 5.050028)
			(end 5.050028 5.050028)
			(stroke
				(width 0.1)
				(type default)
			)
			(layer "F.Fab")
		)
		(fp_poly
			(pts
				(xy -7.62 -4.258056) (xy -7.62 -3.242056) (xy -6.604 -3.750056)
			)
			(stroke
				(width 0)
				(type default)
			)
			(fill yes)
			(layer "F.Fab")
		)
		(pad "1" smd rect
			(at -5.724906 -3.750056)
			(size 0.2794 1.3716)
			(layers "F.Cu" "F.Mask" "F.Paste")
			(net "GND")
		)
		(pad "2" smd rect
			(at -5.724906 -3.24993)
			(size 0.2794 1.3716)
			(layers "F.Cu" "F.Mask" "F.Paste")
			(net "OSC_CLI_IN")
		)
		(pad "3" smd rect
			(at -5.724906 -2.750058)
			(size 0.2794 1.3716)
			(layers "F.Cu" "F.Mask" "F.Paste")
			(net "OSC_CLI_OUT")
		)
		(pad "4" smd rect
			(at -5.724906 -2.249932)
			(size 0.2794 1.3716)
			(layers "F.Cu" "F.Mask" "F.Paste")
			(net "P3V3_CLI_VPHY")
		)
		(pad "5" smd rect
			(at -5.724906 -1.75006)
			(size 0.2794 1.3716)
			(layers "F.Cu" "F.Mask" "F.Paste")
			(net "GND")
		)
		(pad "6" smd rect
			(at -5.724906 -1.249934)
			(size 0.2794 1.3716)
			(layers "F.Cu" "F.Mask" "F.Paste")
			(net "FT4232_CLI_REF")
		)
		(pad "7" smd rect
			(at -5.724906 -0.750062)
			(size 0.2794 1.3716)
			(layers "F.Cu" "F.Mask" "F.Paste")
			(net "USB2_FT4232_CLI_DN")
		)
		(pad "8" smd rect
			(at -5.724906 -0.249936)
			(size 0.2794 1.3716)
			(layers "F.Cu" "F.Mask" "F.Paste")
			(net "USB2_FT4232_CLI_DP")
		)
		(pad "9" smd rect
			(at -5.724906 0.249936)
			(size 0.2794 1.3716)
			(layers "F.Cu" "F.Mask" "F.Paste")
			(net "P3V3_CLI_VPLL")
		)
		(pad "10" smd rect
			(at -5.724906 0.750062)
			(size 0.2794 1.3716)
			(layers "F.Cu" "F.Mask" "F.Paste")
			(net "GND")
		)
		(pad "11" smd rect
			(at -5.724906 1.249934)
			(size 0.2794 1.3716)
			(layers "F.Cu" "F.Mask" "F.Paste")
			(net "GND")
		)
		(pad "12" smd rect
			(at -5.724906 1.75006)
			(size 0.2794 1.3716)
			(layers "F.Cu" "F.Mask" "F.Paste")
			(net "P1V8_CLI_VCORE")
		)
		(pad "13" smd rect
			(at -5.724906 2.249932)
			(size 0.2794 1.3716)
			(layers "F.Cu" "F.Mask" "F.Paste")
			(net "GND")
		)
		(pad "14" smd rect
			(at -5.724906 2.750058)
			(size 0.2794 1.3716)
			(layers "F.Cu" "F.Mask" "F.Paste")
			(net "RST_FT4232_CLI_R_N")
		)
		(pad "15" smd rect
			(at -5.724906 3.24993)
			(size 0.2794 1.3716)
			(layers "F.Cu" "F.Mask" "F.Paste")
			(net "GND")
		)
		(pad "16" smd rect
			(at -5.724906 3.750056)
			(size 0.2794 1.3716)
			(layers "F.Cu" "F.Mask" "F.Paste")
			(net "UART_PEX0_CLI_RX")
		)
		(pad "17" smd rect
			(at -3.750056 5.724906 90)
			(size 0.2794 1.3716)
			(layers "F.Cu" "F.Mask" "F.Paste")
			(net "UART_PEX0_CLI_BUF_TX")
		)
		(pad "18" smd rect
			(at -3.24993 5.724906 90)
			(size 0.2794 1.3716)
			(layers "F.Cu" "F.Mask" "F.Paste")
			(net "Net_8932")
		)
		(pad "19" smd rect
			(at -2.750058 5.724906 90)
			(size 0.2794 1.3716)
			(layers "F.Cu" "F.Mask" "F.Paste")
			(net "Net_8931")
		)
		(pad "20" smd rect
			(at -2.249932 5.724906 90)
			(size 0.2794 1.3716)
			(layers "F.Cu" "F.Mask" "F.Paste")
			(net "P3V3_AUX")
		)
		(pad "21" smd rect
			(at -1.75006 5.724906 90)
			(size 0.2794 1.3716)
			(layers "F.Cu" "F.Mask" "F.Paste")
			(net "Net_8930")
		)
		(pad "22" smd rect
			(at -1.249934 5.724906 90)
			(size 0.2794 1.3716)
			(layers "F.Cu" "F.Mask" "F.Paste")
			(net "Net_8929")
		)
		(pad "23" smd rect
			(at -0.750062 5.724906 90)
			(size 0.2794 1.3716)
			(layers "F.Cu" "F.Mask" "F.Paste")
			(net "Net_8928")
		)
		(pad "24" smd rect
			(at -0.249936 5.724906 90)
			(size 0.2794 1.3716)
			(layers "F.Cu" "F.Mask" "F.Paste")
			(net "Net_8927")
		)
		(pad "25" smd rect
			(at 0.249936 5.724906 90)
			(size 0.2794 1.3716)
			(layers "F.Cu" "F.Mask" "F.Paste")
			(net "GND")
		)
		(pad "26" smd rect
			(at 0.750062 5.724906 90)
			(size 0.2794 1.3716)
			(layers "F.Cu" "F.Mask" "F.Paste")
			(net "UART_PEX1_CLI_RX")
		)
		(pad "27" smd rect
			(at 1.249934 5.724906 90)
			(size 0.2794 1.3716)
			(layers "F.Cu" "F.Mask" "F.Paste")
			(net "UART_PEX1_CLI_BUF_TX")
		)
		(pad "28" smd rect
			(at 1.75006 5.724906 90)
			(size 0.2794 1.3716)
			(layers "F.Cu" "F.Mask" "F.Paste")
			(net "Net_8926")
		)
		(pad "29" smd rect
			(at 2.249932 5.724906 90)
			(size 0.2794 1.3716)
			(layers "F.Cu" "F.Mask" "F.Paste")
			(net "Net_8925")
		)
		(pad "30" smd rect
			(at 2.750058 5.724906 90)
			(size 0.2794 1.3716)
			(layers "F.Cu" "F.Mask" "F.Paste")
			(net "Net_8924")
		)
		(pad "31" smd rect
			(at 3.24993 5.724906 90)
			(size 0.2794 1.3716)
			(layers "F.Cu" "F.Mask" "F.Paste")
			(net "P3V3_AUX")
		)
		(pad "32" smd rect
			(at 3.750056 5.724906 90)
			(size 0.2794 1.3716)
			(layers "F.Cu" "F.Mask" "F.Paste")
			(net "Net_8923")
		)
		(pad "33" smd rect
			(at 5.724906 3.750056)
			(size 0.2794 1.3716)
			(layers "F.Cu" "F.Mask" "F.Paste")
			(net "Net_8922")
		)
		(pad "34" smd rect
			(at 5.724906 3.24993)
			(size 0.2794 1.3716)
			(layers "F.Cu" "F.Mask" "F.Paste")
			(net "Net_8921")
		)
		(pad "35" smd rect
			(at 5.724906 2.750058)
			(size 0.2794 1.3716)
			(layers "F.Cu" "F.Mask" "F.Paste")
			(net "GND")
		)
		(pad "36" smd rect
			(at 5.724906 2.249932)
			(size 0.2794 1.3716)
			(layers "F.Cu" "F.Mask" "F.Paste")
			(net "Net_8907")
		)
		(pad "37" smd rect
			(at 5.724906 1.75006)
			(size 0.2794 1.3716)
			(layers "F.Cu" "F.Mask" "F.Paste")
			(net "P1V8_CLI_VCORE")
		)
		(pad "38" smd rect
			(at 5.724906 1.249934)
			(size 0.2794 1.3716)
			(layers "F.Cu" "F.Mask" "F.Paste")
			(net "UART_PEX2_CLI_RX")
		)
		(pad "39" smd rect
			(at 5.724906 0.750062)
			(size 0.2794 1.3716)
			(layers "F.Cu" "F.Mask" "F.Paste")
			(net "UART_PEX2_CLI_BUF_TX")
		)
		(pad "40" smd rect
			(at 5.724906 0.249936)
			(size 0.2794 1.3716)
			(layers "F.Cu" "F.Mask" "F.Paste")
			(net "Net_8920")
		)
		(pad "41" smd rect
			(at 5.724906 -0.249936)
			(size 0.2794 1.3716)
			(layers "F.Cu" "F.Mask" "F.Paste")
			(net "Net_8919")
		)
		(pad "42" smd rect
			(at 5.724906 -0.750062)
			(size 0.2794 1.3716)
			(layers "F.Cu" "F.Mask" "F.Paste")
			(net "P3V3_AUX")
		)
		(pad "43" smd rect
			(at 5.724906 -1.249934)
			(size 0.2794 1.3716)
			(layers "F.Cu" "F.Mask" "F.Paste")
			(net "Net_8918")
		)
		(pad "44" smd rect
			(at 5.724906 -1.75006)
			(size 0.2794 1.3716)
			(layers "F.Cu" "F.Mask" "F.Paste")
			(net "Net_8917")
		)
		(pad "45" smd rect
			(at 5.724906 -2.249932)
			(size 0.2794 1.3716)
			(layers "F.Cu" "F.Mask" "F.Paste")
			(net "Net_8916")
		)
		(pad "46" smd rect
			(at 5.724906 -2.750058)
			(size 0.2794 1.3716)
			(layers "F.Cu" "F.Mask" "F.Paste")
			(net "Net_8915")
		)
		(pad "47" smd rect
			(at 5.724906 -3.24993)
			(size 0.2794 1.3716)
			(layers "F.Cu" "F.Mask" "F.Paste")
			(net "GND")
		)
		(pad "48" smd rect
			(at 5.724906 -3.750056)
			(size 0.2794 1.3716)
			(layers "F.Cu" "F.Mask" "F.Paste")
			(net "UART_PEX3_CLI_RX")
		)
		(pad "49" smd rect
			(at 3.750056 -5.724906 90)
			(size 0.2794 1.3716)
			(layers "F.Cu" "F.Mask" "F.Paste")
			(net "P1V8_CLI_VCORE")
		)
		(pad "50" smd rect
			(at 3.24993 -5.724906 90)
			(size 0.2794 1.3716)
			(layers "F.Cu" "F.Mask" "F.Paste")
			(net "P3V3_AUX")
		)
		(pad "51" smd rect
			(at 2.750058 -5.724906 90)
			(size 0.2794 1.3716)
			(layers "F.Cu" "F.Mask" "F.Paste")
			(net "GND")
		)
		(pad "52" smd rect
			(at 2.249932 -5.724906 90)
			(size 0.2794 1.3716)
			(layers "F.Cu" "F.Mask" "F.Paste")
			(net "UART_PEX3_CLI_BUF_TX")
		)
		(pad "53" smd rect
			(at 1.75006 -5.724906 90)
			(size 0.2794 1.3716)
			(layers "F.Cu" "F.Mask" "F.Paste")
			(net "Net_8914")
		)
		(pad "54" smd rect
			(at 1.249934 -5.724906 90)
			(size 0.2794 1.3716)
			(layers "F.Cu" "F.Mask" "F.Paste")
			(net "Net_8913")
		)
		(pad "55" smd rect
			(at 0.750062 -5.724906 90)
			(size 0.2794 1.3716)
			(layers "F.Cu" "F.Mask" "F.Paste")
			(net "Net_8912")
		)
		(pad "56" smd rect
			(at 0.249936 -5.724906 90)
			(size 0.2794 1.3716)
			(layers "F.Cu" "F.Mask" "F.Paste")
			(net "P3V3_AUX")
		)
		(pad "57" smd rect
			(at -0.249936 -5.724906 90)
			(size 0.2794 1.3716)
			(layers "F.Cu" "F.Mask" "F.Paste")
			(net "Net_8911")
		)
		(pad "58" smd rect
			(at -0.750062 -5.724906 90)
			(size 0.2794 1.3716)
			(layers "F.Cu" "F.Mask" "F.Paste")
			(net "Net_8910")
		)
		(pad "59" smd rect
			(at -1.249934 -5.724906 90)
			(size 0.2794 1.3716)
			(layers "F.Cu" "F.Mask" "F.Paste")
			(net "Net_8909")
		)
		(pad "60" smd rect
			(at -1.75006 -5.724906 90)
			(size 0.2794 1.3716)
			(layers "F.Cu" "F.Mask" "F.Paste")
			(net "Net_8908")
		)
		(pad "61" smd rect
			(at -2.249932 -5.724906 90)
			(size 0.2794 1.3716)
			(layers "F.Cu" "F.Mask" "F.Paste")
			(net "FT4232_CLI_EEPROM_SDA")
		)
		(pad "62" smd rect
			(at -2.750058 -5.724906 90)
			(size 0.2794 1.3716)
			(layers "F.Cu" "F.Mask" "F.Paste")
			(net "FT4232_CLI_EEPROM_SCL")
		)
		(pad "63" smd rect
			(at -3.24993 -5.724906 90)
			(size 0.2794 1.3716)
			(layers "F.Cu" "F.Mask" "F.Paste")
			(net "FT4232_CLI_EEPROM_CS")
		)
		(pad "64" smd rect
			(at -3.750056 -5.724906 90)
			(size 0.2794 1.3716)
			(layers "F.Cu" "F.Mask" "F.Paste")
			(net "P1V8_CLI_VCORE")
		)
	)
)
